(kicad_pcb
	(version 20260206)
	(generator "pcbnew")
	(generator_version "10.0")
	(general
		(thickness 1.6)
		(legacy_teardrops no)
	)
	(paper "A4")
	(title_block
		(title "baseboard — 13948-1b.1110WZS1818.brd")
		(comment 1 "Honey Badger (Wiwynn) / footprints 1233-1239 of 2523")
	)
	(layers
		(0 "F.Cu" signal "TOP")
		(4 "In1.Cu" signal "L2GND")
		(6 "In2.Cu" signal "L3")
		(8 "In3.Cu" signal "L4VCC")
		(10 "In4.Cu" signal "L5VCC")
		(12 "In5.Cu" signal "L6")
		(14 "In6.Cu" signal "L7GND")
		(2 "B.Cu" signal "BOTTOM")
		(9 "F.Adhes" user "F.Adhesive")
		(11 "B.Adhes" user "B.Adhesive")
		(13 "F.Paste" user "Package Geometry/Pastemask Top")
		(15 "B.Paste" user "Package Geometry/Pastemask Bottom")
		(5 "F.SilkS" user "Ref Des/Silkscreen Top")
		(7 "B.SilkS" user "Ref Des/Silkscreen Bottom")
		(1 "F.Mask" user "Board Geometry/Soldermask Top")
		(3 "B.Mask" user "Board Geometry/Soldermask Bottom")
		(17 "Dwgs.User" user "User.Drawings")
		(19 "Cmts.User" user "User.Comments")
		(21 "Eco1.User" user "User.Eco1")
		(23 "Eco2.User" user "User.Eco2")
		(25 "Edge.Cuts" user "Board Geometry/Outline")
		(27 "Margin" user)
		(31 "F.CrtYd" user "Package Geometry/Place Bound Top")
		(29 "B.CrtYd" user "Package Geometry/Place Bound Bottom")
		(35 "F.Fab" user "Ref Des/Assembly Top")
		(33 "B.Fab" user "Ref Des/Assembly Bottom")
	)
	(footprint ""
		(layer "F.Cu")
		(at 180.721 -145.288 -90)
		(property "Reference" "SR919"
			(at 0 0 270)
			(layer "F.SilkS")
			(hide yes)
			(effects
				(font
					(size 1.27 1.27)
				)
			)
		)
		(property "Value" "200KR2F-L-GP"
			(at 0.064008 -3.993896 270)
			(unlocked yes)
			(layer "F.Fab")
			(hide yes)
			(effects
				(font
					(size 1.016 1.016)
					(thickness 0.1524)
				)
			)
		)
		(property "Device Type" "R402H16"
			(at 0.064008 -5.517896 270)
			(unlocked yes)
			(layer "F.Fab")
			(hide yes)
			(effects
				(font
					(size 1.016 1.016)
					(thickness 0.1524)
				)
			)
		)
		(duplicate_pad_numbers_are_jumpers no)
		(fp_line
			(start -0.508 -0.9398)
			(end -0.508 0.9398)
			(stroke
				(width 0.1524)
				(type default)
			)
			(layer "F.SilkS")
		)
		(fp_line
			(start 0.508 -0.9398)
			(end -0.508 -0.9398)
			(stroke
				(width 0.1524)
				(type default)
			)
			(layer "F.SilkS")
		)
		(fp_rect
			(start -0.508 0.9398)
			(end 0.508 -0.9398)
			(stroke
				(width 0)
				(type default)
			)
			(fill no)
			(layer "F.CrtYd")
		)
		(fp_rect
			(start -0.508 0.9398)
			(end 0.508 -0.9398)
			(stroke
				(width 0)
				(type default)
			)
			(fill no)
			(layer "F.Fab")
		)
		(pad "1" smd custom
			(at 0 -0.4445 270)
			(size 0.1397 0.1397)
			(layers "F.Cu" "F.Mask" "F.Paste")
			(net "EXP_I2C_VREF_3")
			(options
				(clearance outline)
				(anchor circle)
			)
			(primitives
				(gr_poly
					(pts
						(arc
							(start -0.1778 -0.2794)
							(mid -0.249642 -0.249642)
							(end -0.2794 -0.1778)
						)
						(arc
							(start -0.2794 0.1778)
							(mid -0.249642 0.249642)
							(end -0.1778 0.2794)
						)
						(arc
							(start 0.1778 0.2794)
							(mid 0.249642 0.249642)
							(end 0.2794 0.1778)
						)
						(arc
							(start 0.2794 -0.1778)
							(mid 0.249642 -0.249642)
							(end 0.1778 -0.2794)
						)
					)
					(width 0)
					(fill yes)
				)
			)
		)
		(pad "2" smd custom
			(at 0 0.4445 270)
			(size 0.1397 0.1397)
			(layers "F.Cu" "F.Mask" "F.Paste")
			(net "P3V3_STBY")
			(options
				(clearance outline)
				(anchor circle)
			)
			(primitives
				(gr_poly
					(pts
						(arc
							(start -0.1778 -0.2794)
							(mid -0.249642 -0.249642)
							(end -0.2794 -0.1778)
						)
						(arc
							(start -0.2794 0.1778)
							(mid -0.249642 0.249642)
							(end -0.1778 0.2794)
						)
						(arc
							(start 0.1778 0.2794)
							(mid 0.249642 0.249642)
							(end 0.2794 0.1778)
						)
						(arc
							(start 0.2794 -0.1778)
							(mid 0.249642 -0.249642)
							(end 0.1778 -0.2794)
						)
					)
					(width 0)
					(fill yes)
				)
			)
		)
	)
	(footprint ""
		(layer "F.Cu")
		(at 266.065 -181.102 -90)
		(property "Reference" "R523"
			(at 0 0 270)
			(layer "F.SilkS")
			(hide yes)
			(effects
				(font
					(size 1.27 1.27)
				)
			)
		)
		(property "Value" "0R2J-2-GP"
			(at 0.064008 -3.993896 270)
			(unlocked yes)
			(layer "F.Fab")
			(hide yes)
			(effects
				(font
					(size 1.016 1.016)
					(thickness 0.1524)
				)
			)
		)
		(property "Device Type" "R402H16"
			(at 0.064008 -5.517896 270)
			(unlocked yes)
			(layer "F.Fab")
			(hide yes)
			(effects
				(font
					(size 1.016 1.016)
					(thickness 0.1524)
				)
			)
		)
		(duplicate_pad_numbers_are_jumpers no)
		(fp_line
			(start -0.508 -0.9398)
			(end -0.508 0.9398)
			(stroke
				(width 0.1524)
				(type default)
			)
			(layer "F.SilkS")
		)
		(fp_line
			(start 0.508 -0.9398)
			(end -0.508 -0.9398)
			(stroke
				(width 0.1524)
				(type default)
			)
			(layer "F.SilkS")
		)
		(fp_rect
			(start -0.508 0.9398)
			(end 0.508 -0.9398)
			(stroke
				(width 0)
				(type default)
			)
			(fill no)
			(layer "F.CrtYd")
		)
		(fp_rect
			(start -0.508 0.9398)
			(end 0.508 -0.9398)
			(stroke
				(width 0)
				(type default)
			)
			(fill no)
			(layer "F.Fab")
		)
		(pad "1" smd custom
			(at 0 -0.4445 270)
			(size 0.1397 0.1397)
			(layers "F.Cu" "F.Mask" "F.Paste")
			(net "EXP_TRAY_ID_BMC")
			(options
				(clearance outline)
				(anchor circle)
			)
			(primitives
				(gr_poly
					(pts
						(arc
							(start -0.1778 -0.2794)
							(mid -0.249642 -0.249642)
							(end -0.2794 -0.1778)
						)
						(arc
							(start -0.2794 0.1778)
							(mid -0.249642 0.249642)
							(end -0.1778 0.2794)
						)
						(arc
							(start 0.1778 0.2794)
							(mid 0.249642 0.249642)
							(end 0.2794 0.1778)
						)
						(arc
							(start 0.2794 -0.1778)
							(mid 0.249642 -0.249642)
							(end 0.1778 -0.2794)
						)
					)
					(width 0)
					(fill yes)
				)
			)
		)
		(pad "2" smd custom
			(at 0 0.4445 270)
			(size 0.1397 0.1397)
			(layers "F.Cu" "F.Mask" "F.Paste")
			(net "EXP_TRAY_ID")
			(options
				(clearance outline)
				(anchor circle)
			)
			(primitives
				(gr_poly
					(pts
						(arc
							(start -0.1778 -0.2794)
							(mid -0.249642 -0.249642)
							(end -0.2794 -0.1778)
						)
						(arc
							(start -0.2794 0.1778)
							(mid -0.249642 0.249642)
							(end -0.1778 0.2794)
						)
						(arc
							(start 0.1778 0.2794)
							(mid 0.249642 0.249642)
							(end 0.2794 0.1778)
						)
						(arc
							(start 0.2794 -0.1778)
							(mid 0.249642 -0.249642)
							(end 0.1778 -0.2794)
						)
					)
					(width 0)
					(fill yes)
				)
			)
		)
	)
	(footprint ""
		(layer "F.Cu")
		(at 118.12397 -79.629)
		(property "Reference" "STP113"
			(at 0 0 0)
			(layer "F.SilkS")
			(hide yes)
			(effects
				(font
					(size 1.27 1.27)
				)
			)
		)
		(property "Value" "TPAD28"
			(at 0.0127 -1.8034 0)
			(unlocked yes)
			(layer "F.Fab")
			(hide yes)
			(effects
				(font
					(size 1.016 1.016)
					(thickness 0.1524)
				)
			)
		)
		(property "Device Type" "TPAD28"
			(at 0.0127 -3.3274 0)
			(unlocked yes)
			(layer "F.Fab")
			(hide yes)
			(effects
				(font
					(size 1.016 1.016)
					(thickness 0.1524)
				)
			)
		)
		(duplicate_pad_numbers_are_jumpers no)
		(fp_poly
			(pts
				(arc
					(start 0.3556 0)
					(mid -0.3556 0)
					(end 0.3556 0)
				)
			)
			(stroke
				(width 0)
				(type default)
			)
			(fill no)
			(layer "F.CrtYd")
		)
		(fp_poly
			(pts
				(arc
					(start 0.6096 0)
					(mid -0.6096 0)
					(end 0.6096 0)
				)
			)
			(stroke
				(width 0)
				(type default)
			)
			(fill no)
			(layer "F.Fab")
		)
		(pad "1" smd circle
			(at 0 0)
			(size 0.7112 0.7112)
			(layers "F.Cu" "F.Mask" "F.Paste")
			(net "TEST_MUX_46")
		)
	)
	(footprint ""
		(layer "F.Cu")
		(at 253.619 -132.08)
		(property "Reference" "U193"
			(at 0 0 0)
			(layer "F.SilkS")
			(hide yes)
			(effects
				(font
					(size 1.27 1.27)
				)
			)
		)
		(property "Value" "74HC2G125DP-GP"
			(at 0 -9.0932 0)
			(unlocked yes)
			(layer "F.Fab")
			(hide yes)
			(effects
				(font
					(size 1.016 1.016)
					(thickness 0.1524)
				)
			)
		)
		(property "Device Type" "SSOIC8H44"
			(at 0 -10.6172 0)
			(unlocked yes)
			(layer "F.Fab")
			(hide yes)
			(effects
				(font
					(size 1.016 1.016)
					(thickness 0.1524)
				)
			)
		)
		(duplicate_pad_numbers_are_jumpers no)
		(fp_line
			(start -1.7018 -0.5842)
			(end -1.7018 0.5842)
			(stroke
				(width 0.1524)
				(type default)
			)
			(layer "F.SilkS")
		)
		(fp_line
			(start -1.7018 -0.5842)
			(end 1.0668 -0.5842)
			(stroke
				(width 0.1524)
				(type default)
			)
			(layer "F.SilkS")
		)
		(fp_line
			(start -1.524 0.5842)
			(end -1.524 2.286)
			(stroke
				(width 0.508)
				(type default)
			)
			(layer "F.SilkS")
		)
		(fp_line
			(start -1.397 0)
			(end -1.7018 -0.3048)
			(stroke
				(width 0.1524)
				(type default)
			)
			(layer "F.SilkS")
		)
		(fp_line
			(start -1.397 0)
			(end -1.7018 0.3048)
			(stroke
				(width 0.1524)
				(type default)
			)
			(layer "F.SilkS")
		)
		(fp_line
			(start 1.0668 -0.5842)
			(end 1.0668 0.5842)
			(stroke
				(width 0.1524)
				(type default)
			)
			(layer "F.SilkS")
		)
		(fp_line
			(start 1.0668 0.5842)
			(end -1.7018 0.5842)
			(stroke
				(width 0.1524)
				(type default)
			)
			(layer "F.SilkS")
		)
		(fp_poly
			(pts
				(xy -1.1684 0.5842) (xy 1.0668 0.5842) (xy 1.0668 -0.5842) (xy -1.1684 -0.5842)
			)
			(stroke
				(width 0)
				(type default)
			)
			(fill yes)
			(layer "F.SilkS")
		)
		(fp_rect
			(start -1.778 2.54)
			(end 1.778 -2.54)
			(stroke
				(width 0)
				(type default)
			)
			(fill no)
			(layer "F.CrtYd")
		)
		(fp_poly
			(pts
				(xy -1.778 -2.54) (xy 1.778 -2.54) (xy 1.778 2.54) (xy -1.778 2.54)
			)
			(stroke
				(width 0)
				(type default)
			)
			(fill no)
			(layer "F.Fab")
		)
		(pad "1" smd rect
			(at -0.97536 1.6256)
			(size 0.3556 1.524)
			(layers "F.Cu" "F.Mask" "F.Paste")
			(net "DEBUG_OE_2_N")
		)
		(pad "2" smd rect
			(at -0.32512 1.6256)
			(size 0.3556 1.524)
			(layers "F.Cu" "F.Mask" "F.Paste")
			(net "CPU_U193_PIN2_TX")
		)
		(pad "3" smd rect
			(at 0.32512 1.6256)
			(size 0.3556 1.524)
			(layers "F.Cu" "F.Mask" "F.Paste")
			(net "CPU_U193_PIN3_RX")
		)
		(pad "4" smd rect
			(at 0.97536 1.6256)
			(size 0.3556 1.524)
			(layers "F.Cu" "F.Mask" "F.Paste")
			(net "GND")
		)
		(pad "5" smd rect
			(at 0.97536 -1.6256)
			(size 0.3556 1.524)
			(layers "F.Cu" "F.Mask" "F.Paste")
			(net "CPU_U193_PIN5_TX")
		)
		(pad "6" smd rect
			(at 0.32512 -1.6256)
			(size 0.3556 1.524)
			(layers "F.Cu" "F.Mask" "F.Paste")
			(net "CPU_U193_PIN6_RX")
		)
		(pad "7" smd rect
			(at -0.32512 -1.6256)
			(size 0.3556 1.524)
			(layers "F.Cu" "F.Mask" "F.Paste")
			(net "DEBUG_OE_2_N")
		)
		(pad "8" smd rect
			(at -0.97536 -1.6256)
			(size 0.3556 1.524)
			(layers "F.Cu" "F.Mask" "F.Paste")
			(net "P3V3_STBY")
		)
	)
	(footprint ""
		(layer "F.Cu")
		(at 274.828 -104.648 90)
		(property "Reference" "PC192"
			(at 0 0 90)
			(layer "F.SilkS")
			(hide yes)
			(effects
				(font
					(size 1.27 1.27)
				)
			)
		)
		(property "Value" "SCD47U25V3KX-3-GP"
			(at 0 -2.8194 90)
			(unlocked yes)
			(layer "F.Fab")
			(hide yes)
			(effects
				(font
					(size 1.016 1.016)
					(thickness 0.1524)
				)
			)
		)
		(property "Device Type" "C603H36"
			(at 0 -4.3434 90)
			(unlocked yes)
			(layer "F.Fab")
			(hide yes)
			(effects
				(font
					(size 1.016 1.016)
					(thickness 0.1524)
				)
			)
		)
		(duplicate_pad_numbers_are_jumpers no)
		(fp_line
			(start 0.508 0)
			(end -0.508 0)
			(stroke
				(width 0.2032)
				(type default)
			)
			(layer "F.SilkS")
		)
		(fp_rect
			(start -0.5842 1.3335)
			(end 0.5842 -1.3335)
			(stroke
				(width 0)
				(type default)
			)
			(fill no)
			(layer "F.CrtYd")
		)
		(fp_rect
			(start -0.5842 1.3335)
			(end 0.5842 -1.3335)
			(stroke
				(width 0)
				(type default)
			)
			(fill no)
			(layer "F.Fab")
		)
		(pad "1" smd custom
			(at 0 -0.762 90)
			(size 0.2159 0.2159)
			(layers "F.Cu" "F.Mask" "F.Paste")
			(net "P1V8_C_EN_LV")
			(options
				(clearance outline)
				(anchor circle)
			)
			(primitives
				(gr_poly
					(pts
						(arc
							(start -0.3302 -0.4318)
							(mid -0.402042 -0.402042)
							(end -0.4318 -0.3302)
						)
						(arc
							(start -0.4318 0.3302)
							(mid -0.402042 0.402042)
							(end -0.3302 0.4318)
						)
						(arc
							(start 0.3302 0.4318)
							(mid 0.402042 0.402042)
							(end 0.4318 0.3302)
						)
						(arc
							(start 0.4318 -0.3302)
							(mid 0.402042 -0.402042)
							(end 0.3302 -0.4318)
						)
					)
					(width 0)
					(fill yes)
				)
			)
		)
		(pad "2" smd custom
			(at 0 0.762 90)
			(size 0.2159 0.2159)
			(layers "F.Cu" "F.Mask" "F.Paste")
			(net "P1V8_C")
			(options
				(clearance outline)
				(anchor circle)
			)
			(primitives
				(gr_poly
					(pts
						(arc
							(start -0.3302 -0.4318)
							(mid -0.402042 -0.402042)
							(end -0.4318 -0.3302)
						)
						(arc
							(start -0.4318 0.3302)
							(mid -0.402042 0.402042)
							(end -0.3302 0.4318)
						)
						(arc
							(start 0.3302 0.4318)
							(mid 0.402042 0.402042)
							(end 0.4318 0.3302)
						)
						(arc
							(start 0.4318 -0.3302)
							(mid 0.402042 -0.402042)
							(end 0.3302 -0.4318)
						)
					)
					(width 0)
					(fill yes)
				)
			)
		)
	)
	(footprint ""
		(layer "F.Cu")
		(at 114.497612 -221.996 180)
		(property "Reference" "SR880"
			(at 0 0 180)
			(layer "F.SilkS")
			(hide yes)
			(effects
				(font
					(size 1.27 1.27)
				)
			)
		)
		(property "Value" "0R2J-2-GP"
			(at 0.064008 -3.993896 180)
			(unlocked yes)
			(layer "F.Fab")
			(hide yes)
			(effects
				(font
					(size 1.016 1.016)
					(thickness 0.1524)
				)
			)
		)
		(property "Device Type" "R402H16"
			(at 0.064008 -5.517896 180)
			(unlocked yes)
			(layer "F.Fab")
			(hide yes)
			(effects
				(font
					(size 1.016 1.016)
					(thickness 0.1524)
				)
			)
		)
		(duplicate_pad_numbers_are_jumpers no)
		(fp_line
			(start 0.508 -0.9398)
			(end -0.508 -0.9398)
			(stroke
				(width 0.1524)
				(type default)
			)
			(layer "F.SilkS")
		)
		(fp_line
			(start -0.508 -0.9398)
			(end -0.508 0.9398)
			(stroke
				(width 0.1524)
				(type default)
			)
			(layer "F.SilkS")
		)
		(fp_rect
			(start -0.508 0.9398)
			(end 0.508 -0.9398)
			(stroke
				(width 0)
				(type default)
			)
			(fill no)
			(layer "F.CrtYd")
		)
		(fp_rect
			(start -0.508 0.9398)
			(end 0.508 -0.9398)
			(stroke
				(width 0)
				(type default)
			)
			(fill no)
			(layer "F.Fab")
		)
		(pad "1" smd custom
			(at 0 -0.4445 180)
			(size 0.1397 0.1397)
			(layers "F.Cu" "F.Mask" "F.Paste")
			(net "REDV_TX8_P")
			(options
				(clearance outline)
				(anchor circle)
			)
			(primitives
				(gr_poly
					(pts
						(arc
							(start -0.1778 -0.2794)
							(mid -0.249642 -0.249642)
							(end -0.2794 -0.1778)
						)
						(arc
							(start -0.2794 0.1778)
							(mid -0.249642 0.249642)
							(end -0.1778 0.2794)
						)
						(arc
							(start 0.1778 0.2794)
							(mid 0.249642 0.249642)
							(end 0.2794 0.1778)
						)
						(arc
							(start 0.2794 -0.1778)
							(mid 0.249642 -0.249642)
							(end 0.1778 -0.2794)
						)
					)
					(width 0)
					(fill yes)
				)
			)
		)
		(pad "2" smd custom
			(at 0 0.4445 180)
			(size 0.1397 0.1397)
			(layers "F.Cu" "F.Mask" "F.Paste")
			(net "SAS_HDD_CONN_TX8_P")
			(options
				(clearance outline)
				(anchor circle)
			)
			(primitives
				(gr_poly
					(pts
						(arc
							(start -0.1778 -0.2794)
							(mid -0.249642 -0.249642)
							(end -0.2794 -0.1778)
						)
						(arc
							(start -0.2794 0.1778)
							(mid -0.249642 0.249642)
							(end -0.1778 0.2794)
						)
						(arc
							(start 0.1778 0.2794)
							(mid 0.249642 0.249642)
							(end 0.2794 0.1778)
						)
						(arc
							(start 0.2794 -0.1778)
							(mid 0.249642 -0.249642)
							(end 0.1778 -0.2794)
						)
					)
					(width 0)
					(fill yes)
				)
			)
		)
	)
	(footprint ""
		(layer "F.Cu")
		(at 200.533 -224.282 180)
		(property "Reference" "R2055"
			(at 0 0 180)
			(layer "F.SilkS")
			(hide yes)
			(effects
				(font
					(size 1.27 1.27)
				)
			)
		)
		(property "Value" "4K7R2F-GP"
			(at 0.064008 -3.993896 180)
			(unlocked yes)
			(layer "F.Fab")
			(hide yes)
			(effects
				(font
					(size 1.016 1.016)
					(thickness 0.1524)
				)
			)
		)
		(property "Device Type" "R402H16"
			(at 0.064008 -5.517896 180)
			(unlocked yes)
			(layer "F.Fab")
			(hide yes)
			(effects
				(font
					(size 1.016 1.016)
					(thickness 0.1524)
				)
			)
		)
		(duplicate_pad_numbers_are_jumpers no)
		(fp_line
			(start 0.508 -0.9398)
			(end -0.508 -0.9398)
			(stroke
				(width 0.1524)
				(type default)
			)
			(layer "F.SilkS")
		)
		(fp_line
			(start -0.508 -0.9398)
			(end -0.508 0.9398)
			(stroke
				(width 0.1524)
				(type default)
			)
			(layer "F.SilkS")
		)
		(fp_rect
			(start -0.508 0.9398)
			(end 0.508 -0.9398)
			(stroke
				(width 0)
				(type default)
			)
			(fill no)
			(layer "F.CrtYd")
		)
		(fp_rect
			(start -0.508 0.9398)
			(end 0.508 -0.9398)
			(stroke
				(width 0)
				(type default)
			)
			(fill no)
			(layer "F.Fab")
		)
		(pad "1" smd custom
			(at 0 -0.4445 180)
			(size 0.1397 0.1397)
			(layers "F.Cu" "F.Mask" "F.Paste")
			(net "FM_BMC_READY_N")
			(options
				(clearance outline)
				(anchor circle)
			)
			(primitives
				(gr_poly
					(pts
						(arc
							(start -0.1778 -0.2794)
							(mid -0.249642 -0.249642)
							(end -0.2794 -0.1778)
						)
						(arc
							(start -0.2794 0.1778)
							(mid -0.249642 0.249642)
							(end -0.1778 0.2794)
						)
						(arc
							(start 0.1778 0.2794)
							(mid 0.249642 0.249642)
							(end 0.2794 0.1778)
						)
						(arc
							(start 0.2794 -0.1778)
							(mid 0.249642 -0.249642)
							(end 0.1778 -0.2794)
						)
					)
					(width 0)
					(fill yes)
				)
			)
		)
		(pad "2" smd custom
			(at 0 0.4445 180)
			(size 0.1397 0.1397)
			(layers "F.Cu" "F.Mask" "F.Paste")
			(net "P3V3_STBY")
			(options
				(clearance outline)
				(anchor circle)
			)
			(primitives
				(gr_poly
					(pts
						(arc
							(start -0.1778 -0.2794)
							(mid -0.249642 -0.249642)
							(end -0.2794 -0.1778)
						)
						(arc
							(start -0.2794 0.1778)
							(mid -0.249642 0.249642)
							(end -0.1778 0.2794)
						)
						(arc
							(start 0.1778 0.2794)
							(mid 0.249642 0.249642)
							(end 0.2794 0.1778)
						)
						(arc
							(start 0.2794 -0.1778)
							(mid 0.249642 -0.249642)
							(end 0.1778 -0.2794)
						)
					)
					(width 0)
					(fill yes)
				)
			)
		)
	)
)
